#ISCELL
  pure_quanta quanta_title_block_c *
  *
#ISCELL
  standard offpage *
  page56_i10
#CELL
  pure_quanta q_res *
  page56_i11
#ISCELL
  standard offpage *
  page56_i12
#CELL
  pure_quanta genoa_sp5 *
  page56_i8
